# BASEBOARD_FAB2 (Tioga Pass) — schematic netlist excerpt (pin names and nets, part order shuffled) for the footprints in the layout excerpt that follows; sources: Cadence DE-HDL packaged netlist, KiCad conversion of Wiwynn_Tioga_Pass_MB.brd

C9U7  CAP_A  0.01UF 25V 10% X7R  pkg 0402V  page 79 : A = M_H_VREF ; B = GND
C25W41  CAP  1.0UF 16V 10% X6S  pkg 0402  page 149 : A = VCC_D_3V3 ; B = GND

(kicad_pcb
	(version 20260206)
	(generator "pcbnew")
	(generator_version "10.0")
	(general
		(thickness 1.6)
		(legacy_teardrops no)
	)
	(paper "A4")
	(title_block
		(title "Wiwynn_Tioga_Pass_MB.brd")
		(comment 1 "Tioga Pass / footprints 4082-4083 of 4770")
	)
	(layers
		(0 "F.Cu" signal "TOP")
		(4 "In1.Cu" signal "L2GND")
		(6 "In2.Cu" signal "L3")
		(8 "In3.Cu" signal "L4GND")
		(10 "In4.Cu" signal "L5")
		(12 "In5.Cu" signal "L6GND")
		(14 "In6.Cu" signal "L7VCC")
		(16 "In7.Cu" signal "L8VCC")
		(18 "In8.Cu" signal "L9GND")
		(20 "In9.Cu" signal "L10")
		(22 "In10.Cu" signal "L11GND")
		(24 "In11.Cu" signal "L12")
		(26 "In12.Cu" signal "L13GND")
		(2 "B.Cu" signal "BOTTOM")
		(9 "F.Adhes" user "F.Adhesive")
		(11 "B.Adhes" user "B.Adhesive")
		(13 "F.Paste" user "Package Geometry/Pastemask Top")
		(15 "B.Paste" user "Package Geometry/Pastemask Bottom")
		(5 "F.SilkS" user "Ref Des/Silkscreen Top")
		(7 "B.SilkS" user "Ref Des/Silkscreen Bottom")
		(1 "F.Mask" user "Board Geometry/Soldermask Top")
		(3 "B.Mask" user "Board Geometry/Soldermask Bottom")
		(17 "Dwgs.User" user "User.Drawings")
		(19 "Cmts.User" user "User.Comments")
		(21 "Eco1.User" user "User.Eco1")
		(23 "Eco2.User" user "User.Eco2")
		(25 "Edge.Cuts" user "Board Geometry/Outline")
		(27 "Margin" user)
		(31 "F.CrtYd" user "Package Geometry/Place Bound Top")
		(29 "B.CrtYd" user "Package Geometry/Place Bound Bottom")
		(35 "F.Fab" user "Ref Des/Assembly Top")
		(33 "B.Fab" user "Ref Des/Assembly Bottom")
	)
	(footprint ""
		(layer "B.Cu")
		(at 417.81222 -39.0398 180)
		(property "Reference" "C25W41"
			(at 0.8382 -0.67818 180)
			(unlocked yes)
			(layer "B.SilkS")
			(effects
				(font
					(size 0.4064 0.254)
					(thickness 0.1524)
				)
				(justify left mirror)
			)
		)
		(property "Value" ""
			(at 0 0 0)
			(layer "B.Fab")
			(effects
				(font
					(size 1.27 1.27)
				)
				(justify mirror)
			)
		)
		(duplicate_pad_numbers_are_jumpers no)
		(fp_poly
			(pts
				(xy -0.3048 -0.1016) (xy -0.3048 0.9906) (xy 0.3048 0.9906) (xy 0.3048 -0.1016)
			)
			(stroke
				(width 0)
				(type default)
			)
			(fill no)
			(layer "B.CrtYd")
		)
		(fp_line
			(start 0.3048 0.9906)
			(end -0.3048 0.9906)
			(stroke
				(width 0.1)
				(type default)
			)
			(layer "B.Fab")
		)
		(fp_line
			(start 0.3048 -0.1016)
			(end 0.3048 0.9906)
			(stroke
				(width 0.1)
				(type default)
			)
			(layer "B.Fab")
		)
		(fp_line
			(start -0.3048 0.9906)
			(end -0.3048 -0.1016)
			(stroke
				(width 0.1)
				(type default)
			)
			(layer "B.Fab")
		)
		(fp_line
			(start -0.3048 -0.1016)
			(end 0.3048 -0.1016)
			(stroke
				(width 0.1)
				(type default)
			)
			(layer "B.Fab")
		)
		(pad "1" smd rect
			(at 0 0)
			(size 0.508 0.508)
			(layers "B.Cu" "B.Mask" "B.Paste")
			(net "VCC_D_3V3")
		)
		(pad "2" smd rect
			(at 0 0.889)
			(size 0.508 0.508)
			(layers "B.Cu" "B.Mask" "B.Paste")
			(net "GND")
		)
		(zone
			(layer "B.Cu")
			(hatch none 0.5)
			(connect_pads
				(clearance 0)
			)
			(min_thickness 0.25)
			(keepout
				(tracks not_allowed)
				(vias allowed)
				(pads allowed)
				(copperpour not_allowed)
				(footprints allowed)
			)
			(placement
				(enabled no)
				(sheetname "")
			)
			(fill
				(thermal_gap 0.5)
				(thermal_bridge_width 0.5)
				(island_removal_mode 0)
			)
			(polygon
				(pts
					(xy 417.55822 -39.6748) (xy 418.06622 -39.6748) (xy 418.06622 -39.2938) (xy 417.55822 -39.2938)
				)
			)
		)
		(zone
			(layer "B.Cu")
			(hatch none 0.5)
			(connect_pads
				(clearance 0)
			)
			(min_thickness 0.25)
			(keepout
				(tracks allowed)
				(vias not_allowed)
				(pads allowed)
				(copperpour not_allowed)
				(footprints allowed)
			)
			(placement
				(enabled no)
				(sheetname "")
			)
			(fill
				(thermal_gap 0.5)
				(thermal_bridge_width 0.5)
				(island_removal_mode 0)
			)
			(polygon
				(pts
					(xy 417.55822 -39.2938) (xy 418.06622 -39.2938) (xy 418.06622 -39.6748) (xy 417.55822 -39.6748)
				)
			)
		)
	)
	(footprint ""
		(layer "B.Cu")
		(at 30.452568 -8.122412 90)
		(property "Reference" "C9U7"
			(at 0 0 90)
			(layer "B.SilkS")
			(hide yes)
			(effects
				(font
					(size 1.27 1.27)
				)
				(justify mirror)
			)
		)
		(property "Value" ""
			(at 0 0 90)
			(layer "B.Fab")
			(effects
				(font
					(size 1.27 1.27)
				)
				(justify mirror)
			)
		)
		(duplicate_pad_numbers_are_jumpers no)
		(fp_poly
			(pts
				(xy -0.3048 -0.1016) (xy -0.3048 0.9906) (xy 0.3048 0.9906) (xy 0.3048 -0.1016)
			)
			(stroke
				(width 0)
				(type default)
			)
			(fill no)
			(layer "B.CrtYd")
		)
		(fp_line
			(start 0.3048 -0.1016)
			(end 0.3048 0.9906)
			(stroke
				(width 0.1)
				(type default)
			)
			(layer "B.Fab")
		)
		(fp_line
			(start -0.3048 -0.1016)
			(end 0.3048 -0.1016)
			(stroke
				(width 0.1)
				(type default)
			)
			(layer "B.Fab")
		)
		(fp_line
			(start 0.3048 0.9906)
			(end -0.3048 0.9906)
			(stroke
				(width 0.1)
				(type default)
			)
			(layer "B.Fab")
		)
		(fp_line
			(start -0.3048 0.9906)
			(end -0.3048 -0.1016)
			(stroke
				(width 0.1)
				(type default)
			)
			(layer "B.Fab")
		)
		(pad "1" smd rect
			(at 0 0 270)
			(size 0.508 0.508)
			(layers "B.Cu" "B.Mask" "B.Paste")
			(net "M_H_VREF")
		)
		(pad "2" smd rect
			(at 0 0.889 270)
			(size 0.508 0.508)
			(layers "B.Cu" "B.Mask" "B.Paste")
			(net "GND")
		)
		(zone
			(layer "B.Cu")
			(hatch none 0.5)
			(connect_pads
				(clearance 0)
			)
			(min_thickness 0.25)
			(keepout
				(tracks allowed)
				(vias not_allowed)
				(pads allowed)
				(copperpour not_allowed)
				(footprints allowed)
			)
			(placement
				(enabled no)
				(sheetname "")
			)
			(fill
				(thermal_gap 0.5)
				(thermal_bridge_width 0.5)
				(island_removal_mode 0)
			)
			(polygon
				(pts
					(xy 30.706568 -8.376412) (xy 30.706568 -7.868412) (xy 31.087568 -7.868412) (xy 31.087568 -8.376412)
				)
			)
		)
		(zone
			(layer "B.Cu")
			(hatch none 0.5)
			(connect_pads
				(clearance 0)
			)
			(min_thickness 0.25)
			(keepout
				(tracks not_allowed)
				(vias allowed)
				(pads allowed)
				(copperpour not_allowed)
				(footprints allowed)
			)
			(placement
				(enabled no)
				(sheetname "")
			)
			(fill
				(thermal_gap 0.5)
				(thermal_bridge_width 0.5)
				(island_removal_mode 0)
			)
			(polygon
				(pts
					(xy 31.087568 -8.376412) (xy 31.087568 -7.868412) (xy 30.706568 -7.868412) (xy 30.706568 -8.376412)
				)
			)
		)
	)
)
